# BASEBOARD_FAB2 (Tioga Pass) — schematic netlist excerpt (pin names and nets, part order shuffled) for the footprints in the layout excerpt that follows; sources: Cadence DE-HDL packaged netlist, KiCad conversion of Wiwynn_Tioga_Pass_MB.brd

R8B26  RES  3.3K 5% CHIP  pkg 0402  page 138 : A = P3V3_STBY ; B = SMB_HOST_STBY_LVC3_SCL_R5

(kicad_pcb
	(version 20260206)
	(generator "pcbnew")
	(generator_version "10.0")
	(general
		(thickness 1.6)
		(legacy_teardrops no)
	)
	(paper "A4")
	(title_block
		(title "Wiwynn_Tioga_Pass_MB.brd")
		(comment 1 "Tioga Pass / footprints 191-192 of 4770")
	)
	(layers
		(0 "F.Cu" signal "TOP")
		(4 "In1.Cu" signal "L2GND")
		(6 "In2.Cu" signal "L3")
		(8 "In3.Cu" signal "L4GND")
		(10 "In4.Cu" signal "L5")
		(12 "In5.Cu" signal "L6GND")
		(14 "In6.Cu" signal "L7VCC")
		(16 "In7.Cu" signal "L8VCC")
		(18 "In8.Cu" signal "L9GND")
		(20 "In9.Cu" signal "L10")
		(22 "In10.Cu" signal "L11GND")
		(24 "In11.Cu" signal "L12")
		(26 "In12.Cu" signal "L13GND")
		(2 "B.Cu" signal "BOTTOM")
		(9 "F.Adhes" user "F.Adhesive")
		(11 "B.Adhes" user "B.Adhesive")
		(13 "F.Paste" user "Package Geometry/Pastemask Top")
		(15 "B.Paste" user "Package Geometry/Pastemask Bottom")
		(5 "F.SilkS" user "Ref Des/Silkscreen Top")
		(7 "B.SilkS" user "Ref Des/Silkscreen Bottom")
		(1 "F.Mask" user "Board Geometry/Soldermask Top")
		(3 "B.Mask" user "Board Geometry/Soldermask Bottom")
		(17 "Dwgs.User" user "User.Drawings")
		(19 "Cmts.User" user "User.Comments")
		(21 "Eco1.User" user "User.Eco1")
		(23 "Eco2.User" user "User.Eco2")
		(25 "Edge.Cuts" user "Board Geometry/Outline")
		(27 "Margin" user)
		(31 "F.CrtYd" user "Package Geometry/Place Bound Top")
		(29 "B.CrtYd" user "Package Geometry/Place Bound Bottom")
		(35 "F.Fab" user "Ref Des/Assembly Top")
		(33 "B.Fab" user "Ref Des/Assembly Bottom")
	)
	(footprint ""
		(layer "F.Cu")
		(at 9.779 -155.702)
		(property "Reference" ""
			(at 0 0 0)
			(layer "F.SilkS")
			(hide yes)
			(effects
				(font
					(size 1.27 1.27)
				)
			)
		)
		(property "Value" ""
			(at 0 0 0)
			(layer "F.Fab")
			(effects
				(font
					(size 1.27 1.27)
				)
			)
		)
		(duplicate_pad_numbers_are_jumpers no)
		(fp_poly
			(pts
				(arc
					(start 2.032 0)
					(mid -2.032 0)
					(end 2.032 0)
				)
			)
			(stroke
				(width 0)
				(type default)
			)
			(fill no)
			(layer "F.CrtYd")
		)
		(pad "1" smd circle
			(at 0 0)
			(size 1.016 1.016)
			(layers "F.Cu" "F.Mask" "F.Paste")
			(net "Net_384")
		)
		(zone
			(layer "F.Cu")
			(hatch none 0.5)
			(connect_pads
				(clearance 0)
			)
			(min_thickness 0.25)
			(keepout
				(tracks not_allowed)
				(vias allowed)
				(pads allowed)
				(copperpour not_allowed)
				(footprints allowed)
			)
			(placement
				(enabled no)
				(sheetname "")
			)
			(fill
				(thermal_gap 0.5)
				(thermal_bridge_width 0.5)
				(island_removal_mode 0)
			)
			(polygon
				(pts
					(arc
						(start 11.303 -155.702)
						(mid 8.255 -155.702)
						(end 11.303 -155.702)
					)
				)
			)
		)
		(zone
			(layers "F.Cu" "B.Cu" "In1.Cu" "In2.Cu" "In3.Cu" "In4.Cu" "In5.Cu" "In6.Cu"
				"In7.Cu" "In8.Cu" "In9.Cu" "In10.Cu" "In11.Cu" "In12.Cu"
			)
			(hatch none 0.5)
			(connect_pads
				(clearance 0)
			)
			(min_thickness 0.25)
			(keepout
				(tracks allowed)
				(vias not_allowed)
				(pads allowed)
				(copperpour not_allowed)
				(footprints allowed)
			)
			(placement
				(enabled no)
				(sheetname "")
			)
			(fill
				(thermal_gap 0.5)
				(thermal_bridge_width 0.5)
				(island_removal_mode 0)
			)
			(polygon
				(pts
					(arc
						(start 11.303 -155.702)
						(mid 8.255 -155.702)
						(end 11.303 -155.702)
					)
				)
			)
		)
	)
	(footprint ""
		(layer "F.Cu")
		(at 460.121 -1.524 -90)
		(property "Reference" "R8B26"
			(at -0.8382 -0.67818 270)
			(unlocked yes)
			(layer "F.SilkS")
			(effects
				(font
					(size 0.4064 0.254)
					(thickness 0.1524)
				)
				(justify left)
			)
		)
		(property "Value" ""
			(at 0 0 270)
			(layer "F.Fab")
			(effects
				(font
					(size 1.27 1.27)
				)
			)
		)
		(duplicate_pad_numbers_are_jumpers no)
		(fp_poly
			(pts
				(xy -0.2794 -0.1016) (xy 0.2794 -0.1016) (xy 0.2794 0.9906) (xy -0.2794 0.9906)
			)
			(stroke
				(width 0)
				(type default)
			)
			(fill no)
			(layer "F.CrtYd")
		)
		(fp_line
			(start -0.2794 0.9906)
			(end 0.2794 0.9906)
			(stroke
				(width 0.1)
				(type default)
			)
			(layer "F.Fab")
		)
		(fp_line
			(start 0.2794 0.9906)
			(end 0.2794 -0.1016)
			(stroke
				(width 0.1)
				(type default)
			)
			(layer "F.Fab")
		)
		(fp_line
			(start -0.2794 -0.1016)
			(end -0.2794 0.9906)
			(stroke
				(width 0.1)
				(type default)
			)
			(layer "F.Fab")
		)
		(fp_line
			(start 0.2794 -0.1016)
			(end -0.2794 -0.1016)
			(stroke
				(width 0.1)
				(type default)
			)
			(layer "F.Fab")
		)
		(pad "1" smd rect
			(at 0 0 270)
			(size 0.508 0.508)
			(layers "F.Cu" "F.Mask" "F.Paste")
			(net "P3V3_STBY")
		)
		(pad "2" smd rect
			(at 0 0.889 270)
			(size 0.508 0.508)
			(layers "F.Cu" "F.Mask" "F.Paste")
			(net "SMB_HOST_STBY_LVC3_SCL_R5")
		)
		(zone
			(layer "F.Cu")
			(hatch none 0.5)
			(connect_pads
				(clearance 0)
			)
			(min_thickness 0.25)
			(keepout
				(tracks not_allowed)
				(vias allowed)
				(pads allowed)
				(copperpour not_allowed)
				(footprints allowed)
			)
			(placement
				(enabled no)
				(sheetname "")
			)
			(fill
				(thermal_gap 0.5)
				(thermal_bridge_width 0.5)
				(island_removal_mode 0)
			)
			(polygon
				(pts
					(xy 459.486 -1.778) (xy 459.486 -1.27) (xy 459.867 -1.27) (xy 459.867 -1.778)
				)
			)
		)
		(zone
			(layer "F.Cu")
			(hatch none 0.5)
			(connect_pads
				(clearance 0)
			)
			(min_thickness 0.25)
			(keepout
				(tracks allowed)
				(vias not_allowed)
				(pads allowed)
				(copperpour not_allowed)
				(footprints allowed)
			)
			(placement
				(enabled no)
				(sheetname "")
			)
			(fill
				(thermal_gap 0.5)
				(thermal_bridge_width 0.5)
				(island_removal_mode 0)
			)
			(polygon
				(pts
					(xy 459.867 -1.778) (xy 459.867 -1.27) (xy 459.486 -1.27) (xy 459.486 -1.778)
				)
			)
		)
	)
)
